# S9S_MB_2U (Grand Teton) — schematic parts with pin connectivity, parts 1604–1604 of 6093; source: Cadence DE-HDL packaged netlist (pstxprt.dat, pstxnet.dat, pstchip.dat)

J11  SCONN288_ADR50017P130CC  SCONN288_ADR50017-P130CC IO  pkg DDR288S_1-1VXB  page 92
  1  VIN_BULK0  POWER  = P12V_S3_AUX_CPU0_NVDIMM
  2  RFU0  TRI  = TP_CHF_CPU0_DIMM1_FRU_0
  3  VIN_MGMT  POWER  = P3V3_AUX
  4  HSCL  IN  = I3C_SPD_DDREFGH_CPU0_LVC1_SCL_2
  5  HSDA  BI  = I3C_SPD_DDREFGH_CPU0_LVC1_SDA
  6  VSS0  POWER  = GND
  7  DQ0_A  BI  = M_F_CPU0_SA_DQ<0>
  8  VSS1  POWER  = GND
  9  DQ1_A  BI  = M_F_CPU0_SA_DQ<1>
  10  VSS2  POWER  = GND
  11  DQS0_A_T  BI  = M_F_CPU0_SA_DQS_DP<0>
  12  DQS0_A_C  BI  = M_F_CPU0_SA_DQS_DN<0>
  13  VSS3  POWER  = GND
  14  DQ4_A  BI  = M_F_CPU0_SA_DQ<4>
  15  VSS4  POWER  = GND
  16  DQ5_A  BI  = M_F_CPU0_SA_DQ<5>
  17  VSS5  POWER  = GND
  18  DQ8_A  BI  = M_F_CPU0_SA_DQ<8>
  19  VSS6  POWER  = GND
  20  DQ9_A  BI  = M_F_CPU0_SA_DQ<9>
  21  VSS7  POWER  = GND
  22  DQS1_A_T  BI  = M_F_CPU0_SA_DQS_DP<1>
  23  DQS1_A_C  BI  = M_F_CPU0_SA_DQS_DN<1>
  24  VSS8  POWER  = GND
  25  DQ12_A  BI  = M_F_CPU0_SA_DQ<12>
  26  VSS9  POWER  = GND
  27  DQ13_A  BI  = M_F_CPU0_SA_DQ<13>
  28  VSS10  POWER  = GND
  29  DQ16_A  BI  = M_F_CPU0_SA_DQ<16>
  30  VSS11  POWER  = GND
  31  DQ17_A  BI  = M_F_CPU0_SA_DQ<17>
  32  VSS12  POWER  = GND
  33  DQS2_A_T  BI  = M_F_CPU0_SA_DQS_DP<2>
  34  DQS2_A_C  BI  = M_F_CPU0_SA_DQS_DN<2>
  35  VSS13  POWER  = GND
  36  DQ20_A  BI  = M_F_CPU0_SA_DQ<20>
  37  VSS14  POWER  = GND
  38  DQ21_A  BI  = M_F_CPU0_SA_DQ<21>
  39  VSS15  POWER  = GND
  40  DQ24_A  BI  = M_F_CPU0_SA_DQ<24>
  41  VSS16  POWER  = GND
  42  DQ25_A  BI  = M_F_CPU0_SA_DQ<25>
  43  VSS17  POWER  = GND
  44  DQS3_A_T  BI  = M_F_CPU0_SA_DQS_DP<3>
  45  DQS3_A_C  BI  = M_F_CPU0_SA_DQS_DN<3>
  46  VSS18  POWER  = GND
  47  DQ28_A  BI  = M_F_CPU0_SA_DQ<28>
  48  VSS19  POWER  = GND
  49  DQ29_A  BI  = M_F_CPU0_SA_DQ<29>
  50  VSS20  POWER  = GND
  51  CB0_A  BI  = M_F_CPU0_SA_CB<0>
  52  VSS21  POWER  = GND
  53  CB1_A  BI  = M_F_CPU0_SA_CB<1>
  54  VSS22  POWER  = GND
  55  DQS4_A_T  BI  = M_F_CPU0_SA_DQS_DP<4>
  56  DQS4_A_C  BI  = M_F_CPU0_SA_DQS_DN<4>
  57  VSS23  POWER  = GND
  58  CB4_A  BI  = M_F_CPU0_SA_CB<4>
  59  VSS24  POWER  = GND
  60  CB5_A  BI  = M_F_CPU0_SA_CB<5>
  61  VSS25  POWER  = GND
  62  ALERT_N  OUT  = M_F_CPU0_ALERT_N
  63  VSS26  POWER  = GND
  64  CS0_A_N  IN  = M_F_CPU0_SA_CS_N<0>
  65  VSS27  POWER  = GND
  66  CA0_A  IN  = M_F_CPU0_SA_CA<0>
  67  VSS28  POWER  = GND
  68  CA2_A  IN  = M_F_CPU0_SA_CA<2>
  69  VSS29  POWER  = GND
  70  CA4_A  IN  = M_F_CPU0_SA_CA<4>
  71  VSS30  POWER  = GND
  72  CA6_A  IN  = M_F_CPU0_SA_CA<6>
  73  VSS31  POWER  = GND
  74  PAR_A  IN  = M_F_CPU0_SA_PAR
  75  VSS32  POWER  = GND
  76  CA0_B  IN  = M_F_CPU0_SB_CA<0>
  77  VSS33  POWER  = GND
  78  CA2_B  IN  = M_F_CPU0_SB_CA<2>
  79  VSS34  POWER  = GND
  80  CA4_B  IN  = M_F_CPU0_SB_CA<4>
  81  VSS35  POWER  = GND
  82  CA6_B  IN  = M_F_CPU0_SB_CA<6>
  83  VSS36  POWER  = GND
  84  CS0_B_N  IN  = M_F_CPU0_SB_CS_N<0>
  85  VSS37  POWER  = GND
  86  \lbd||rsp_a_n\  OUT  = M_F_CPU0_SA_RSP<0>
  87  \lbs||rsp_b_n\  OUT  = M_F_CPU0_SB_RSP<0>
  88  VSS38  POWER  = GND
  89  CB4_B  BI  = M_F_CPU0_SB_CB<4>
  90  VSS39  POWER  = GND
  91  CB5_B  BI  = M_F_CPU0_SB_CB<5>
  92  VSS40  POWER  = GND
  93  \dqs9_b_t||tdqs9_b_t||dbi4_b_n\  BI  = M_F_CPU0_SB_DQS_DP<9>
  94  \dqs9_b_c||tdqs9_b_c\  BI  = M_F_CPU0_SB_DQS_DN<9>
  95  VSS41  POWER  = GND
  96  CB0_B  BI  = M_F_CPU0_SB_CB<0>
  97  VSS42  POWER  = GND
  98  CB1_B  BI  = M_F_CPU0_SB_CB<1>
  99  VSS43  POWER  = GND
  100  DQ0_B  BI  = M_F_CPU0_SB_DQ<0>
  101  VSS44  POWER  = GND
  102  DQ1_B  BI  = M_F_CPU0_SB_DQ<1>
  103  VSS45  POWER  = GND
  104  DQS0_B_T  BI  = M_F_CPU0_SB_DQS_DP<0>
  105  DQS0_B_C  BI  = M_F_CPU0_SB_DQS_DN<0>
  106  VSS46  POWER  = GND
  107  DQ4_B  BI  = M_F_CPU0_SB_DQ<4>
  108  VSS47  POWER  = GND
  109  DQ5_B  BI  = M_F_CPU0_SB_DQ<5>
  110  VSS48  POWER  = GND
  111  DQ8_B  BI  = M_F_CPU0_SB_DQ<8>
  112  VSS49  POWER  = GND
  113  DQ9_B  BI  = M_F_CPU0_SB_DQ<9>
  114  VSS50  POWER  = GND
  115  DQS1_B_T  BI  = M_F_CPU0_SB_DQS_DP<1>
  116  DQS1_B_C  BI  = M_F_CPU0_SB_DQS_DN<1>
  117  VSS51  POWER  = GND
  118  DQ12_B  BI  = M_F_CPU0_SB_DQ<12>
  119  VSS52  POWER  = GND
  120  DQ13_B  BI  = M_F_CPU0_SB_DQ<13>
  121  VSS53  POWER  = GND
  122  DQ16_B  BI  = M_F_CPU0_SB_DQ<16>
  123  VSS54  POWER  = GND
  124  DQ17_B  BI  = M_F_CPU0_SB_DQ<17>
  125  VSS55  POWER  = GND
  126  DQS2_B_T  BI  = M_F_CPU0_SB_DQS_DP<2>
  127  DQS2_B_C  BI  = M_F_CPU0_SB_DQS_DN<2>
  128  VSS56  POWER  = GND
  129  DQ20_B  BI  = M_F_CPU0_SB_DQ<20>
  130  VSS57  POWER  = GND
  131  DQ21_B  BI  = M_F_CPU0_SB_DQ<21>
  132  VSS58  POWER  = GND
  133  DQ24_B  BI  = M_F_CPU0_SB_DQ<24>
  134  VSS59  POWER  = GND
  135  DQ25_B  BI  = M_F_CPU0_SB_DQ<25>
  136  VSS60  POWER  = GND
  137  DQS3_B_T  BI  = M_F_CPU0_SB_DQS_DP<3>
  138  DQS3_B_C  BI  = M_F_CPU0_SB_DQS_DN<3>
  139  VSS61  POWER  = GND
  140  DQ28_B  BI  = M_F_CPU0_SB_DQ<28>
  141  VSS62  POWER  = GND
  142  DQ29_B  BI  = M_F_CPU0_SB_DQ<29>
  143  VSS63  POWER  = GND
  144  RFU1  TRI  = TP_CHF_CPU0_DIMM1_FRU_1
  145  VIN_BULK1  POWER  = P12V_S3_AUX_CPU0_NVDIMM
  146  VIN_BULK2  POWER  = P12V_S3_AUX_CPU0_NVDIMM
  147  \pwr_good||fail_n\  BI  = PWRGD_CHF_CPU0_DIMM1
  148  HSA  IN  = PD_CHF_CPU0_DIMM1_SAA
  149  RFU2  TRI  = TP_CHF_CPU0_DIMM1_FRU_2
  150  RFU3  TRI  = TP_CHF_CPU0_DIMM1_FRU_3
  151  VSS64  POWER  = GND
  152  DQ2_A  BI  = M_F_CPU0_SA_DQ<2>
  153  VSS65  POWER  = GND
  154  DQ3_A  BI  = M_F_CPU0_SA_DQ<3>
  155  VSS66  POWER  = GND
  156  \dqs5_a_c||tdqs5_a_c||dqs5_a_t||tdqs5_a_t\  BI  = M_F_CPU0_SA_DQS_DN<5>
  157  \dqs5_a_t||tdqs5_a_t\  BI  = M_F_CPU0_SA_DQS_DP<5>
  158  VSS67  POWER  = GND
  159  DQ6_A  BI  = M_F_CPU0_SA_DQ<6>
  160  VSS68  POWER  = GND
  161  DQ7_A  BI  = M_F_CPU0_SA_DQ<7>
  162  VSS69  POWER  = GND
  163  DQ10_A  BI  = M_F_CPU0_SA_DQ<10>
  164  VSS70  POWER  = GND
  165  DQ11_A  BI  = M_F_CPU0_SA_DQ<11>
  166  VSS71  POWER  = GND
  167  \dqs6_a_c||tdqs6_a_c||dqs6_a_t||tdqs6_a_t\  BI  = M_F_CPU0_SA_DQS_DN<6>
  168  \dqs6_a_t||tdqs6_a_t\  BI  = M_F_CPU0_SA_DQS_DP<6>
  169  VSS72  POWER  = GND
  170  DQ14_A  BI  = M_F_CPU0_SA_DQ<14>
  171  VSS73  POWER  = GND
  172  DQ15_A  BI  = M_F_CPU0_SA_DQ<15>
  173  VSS74  POWER  = GND
  174  DQ18_A  BI  = M_F_CPU0_SA_DQ<18>
  175  VSS75  POWER  = GND
  176  DQ19_A  BI  = M_F_CPU0_SA_DQ<19>
  177  VSS76  POWER  = GND
  178  \dqs7_a_c||tdqs7_a_c\  BI  = M_F_CPU0_SA_DQS_DN<7>
  179  \dqs7_a_t||tdqs7_a_t\  BI  = M_F_CPU0_SA_DQS_DP<7>
  180  VSS77  POWER  = GND
  181  DQ22_A  BI  = M_F_CPU0_SA_DQ<22>
  182  VSS78  POWER  = GND
  183  DQ23_A  BI  = M_F_CPU0_SA_DQ<23>
  184  VSS79  POWER  = GND
  185  DQ26_A  BI  = M_F_CPU0_SA_DQ<26>
  186  VSS80  POWER  = GND
  187  DQ27_A  BI  = M_F_CPU0_SA_DQ<27>
  188  VSS81  POWER  = GND
  189  \dqs8_a_c||tdqs8_a_c\  BI  = M_F_CPU0_SA_DQS_DN<8>
  190  \dqs8_a_t||tdqs8_a_t\  BI  = M_F_CPU0_SA_DQS_DP<8>
  191  VSS82  POWER  = GND
  192  DQ30_A  BI  = M_F_CPU0_SA_DQ<30>
  193  VSS83  POWER  = GND
  194  DQ31_A  BI  = M_F_CPU0_SA_DQ<31>
  195  VSS84  POWER  = GND
  196  CB2_A  BI  = M_F_CPU0_SA_CB<2>
  197  VSS85  POWER  = GND
  198  CB3_A  BI  = M_F_CPU0_SA_CB<3>
  199  VSS86  POWER  = GND
  200  \dqs9_a_c||tdqs9_a_c\  BI  = M_F_CPU0_SA_DQS_DN<9>
  201  \dqs9_a_t||tdqs9_a_t\  BI  = M_F_CPU0_SA_DQS_DP<9>
  202  VSS87  POWER  = GND
  203  CB6_A  BI  = M_F_CPU0_SA_CB<6>
  204  VSS88  POWER  = GND
  205  CB7_A  BI  = M_F_CPU0_SA_CB<7>
  206  VSS89  POWER  = GND
  207  RESET_N  IN  = RST_M_EF_CPU0_FPGA_N
  208  VSS90  POWER  = GND
  209  CS1_A_N  IN  = M_F_CPU0_SA_CS_N<1>
  210  VSS91  POWER  = GND
  211  CA1_A  IN  = M_F_CPU0_SA_CA<1>
  212  VSS92  POWER  = GND
  213  CA3_A  IN  = M_F_CPU0_SA_CA<3>
  214  VSS93  POWER  = GND
  215  CA5_A  IN  = M_F_CPU0_SA_CA<5>
  216  VSS94  POWER  = GND
  217  CK_T  IN  = M_F_CPU0_CLK_DP<0>
  218  CK_C  IN  = M_F_CPU0_CLK_DN<0>
  219  VSS95  POWER  = GND
  220  RFU4  TRI  = TP_CHF_CPU0_DIMM1_FRU_4
  221  CA1_B  IN  = M_F_CPU0_SB_CA<1>
  222  VSS96  POWER  = GND
  223  CA3_B  IN  = M_F_CPU0_SB_CA<3>
  224  VSS97  POWER  = GND
  225  CA5_B  IN  = M_F_CPU0_SB_CA<5>
  226  VSS98  POWER  = GND
  227  PAR_B  IN  = M_F_CPU0_SB_PAR
  228  VSS99  POWER  = GND
  229  CS1_B_N  IN  = M_F_CPU0_SB_CS_N<1>
  230  VSS100  POWER  = GND
  231  RFU5  TRI  = TP_CHF_CPU0_DIMM1_FRU_5
  232  RFU6  TRI  = TP_CHF_CPU0_DIMM1_FRU_6
  233  VSS101  POWER  = GND
  234  CB6_B  BI  = M_F_CPU0_SB_CB<6>
  235  VSS102  POWER  = GND
  236  CB7_B  BI  = M_F_CPU0_SB_CB<7>
  237  VSS103  POWER  = GND
  238  DQS4_B_C  BI  = M_F_CPU0_SB_DQS_DN<4>
  239  DQS4_B_T  BI  = M_F_CPU0_SB_DQS_DP<4>
  240  VSS104  POWER  = GND
  241  CB2_B  BI  = M_F_CPU0_SB_CB<2>
  242  VSS105  POWER  = GND
  243  CB3_B  BI  = M_F_CPU0_SB_CB<3>
  244  VSS106  POWER  = GND
  245  DQ2_B  BI  = M_F_CPU0_SB_DQ<2>
  246  VSS107  POWER  = GND
  247  DQ3_B  BI  = M_F_CPU0_SB_DQ<3>
  248  VSS108  POWER  = GND
  249  \dqs5_b_c||tdqs5_b_c\  BI  = M_F_CPU0_SB_DQS_DN<5>
  250  \dqs5_b_t||tdqs5_b_t\  BI  = M_F_CPU0_SB_DQS_DP<5>
  251  VSS109  POWER  = GND
  252  DQ6_B  BI  = M_F_CPU0_SB_DQ<6>
  253  VSS110  POWER  = GND
  254  DQ7_B  BI  = M_F_CPU0_SB_DQ<7>
  255  VSS111  POWER  = GND
  256  DQ10_B  BI  = M_F_CPU0_SB_DQ<10>
  257  VSS112  POWER  = GND
  258  DQ11_B  BI  = M_F_CPU0_SB_DQ<11>
  259  VSS113  POWER  = GND
  260  \dqs6_b_c||tdqs6_b_c\  BI  = M_F_CPU0_SB_DQS_DN<6>
  261  \dqs6_b_t||tdqs6_b_t\  BI  = M_F_CPU0_SB_DQS_DP<6>
  262  VSS114  POWER  = GND
  263  DQ14_B  BI  = M_F_CPU0_SB_DQ<14>
  264  VSS115  POWER  = GND
  265  DQ15_B  BI  = M_F_CPU0_SB_DQ<15>
  266  VSS116  POWER  = GND
  267  DQ18_B  BI  = M_F_CPU0_SB_DQ<18>
  268  VSS117  POWER  = GND
  269  DQ19_B  BI  = M_F_CPU0_SB_DQ<19>
  270  VSS118  POWER  = GND
  271  \dqs7_b_c||tdqs7_b_c\  BI  = M_F_CPU0_SB_DQS_DN<7>
  272  \dqs7_b_t||tdqs7_b_t\  BI  = M_F_CPU0_SB_DQS_DP<7>
  273  VSS119  POWER  = GND
  274  DQ22_B  BI  = M_F_CPU0_SB_DQ<22>
  275  VSS120  POWER  = GND
  276  DQ23_B  BI  = M_F_CPU0_SB_DQ<23>
  277  VSS121  POWER  = GND
  278  DQ26_B  BI  = M_F_CPU0_SB_DQ<26>
  279  VSS122  POWER  = GND
  280  DQ27_B  BI  = M_F_CPU0_SB_DQ<27>
  281  VSS123  POWER  = GND
  282  \dqs8_b_c||tdqs8_b_c\  BI  = M_F_CPU0_SB_DQS_DN<8>
  283  \dqs8_b_t||tdqs8_b_t\  BI  = M_F_CPU0_SB_DQS_DP<8>
  284  VSS124  POWER  = GND
  285  DQ30_B  BI  = M_F_CPU0_SB_DQ<30>
  286  VSS125  POWER  = GND
  287  DQ31_B  BI  = M_F_CPU0_SB_DQ<31>
  288  VSS126  POWER  = GND
  G1  G1  POWER  = GND
  G2  G2  POWER  = GND
  G3  G3  POWER  = GND
